(kicad_pcb
	(version 20260206)
	(generator "pcbnew")
	(generator_version "10.0")
	(general
		(thickness 1.6)
		(legacy_teardrops no)
	)
	(paper "A4")
	(title_block
		(title "Wiwynn_Tioga_Pass_MB.brd")
		(comment 1 "Tioga Pass / footprints 2623-2629 of 4770")
	)
	(layers
		(0 "F.Cu" signal "TOP")
		(4 "In1.Cu" signal "L2GND")
		(6 "In2.Cu" signal "L3")
		(8 "In3.Cu" signal "L4GND")
		(10 "In4.Cu" signal "L5")
		(12 "In5.Cu" signal "L6GND")
		(14 "In6.Cu" signal "L7VCC")
		(16 "In7.Cu" signal "L8VCC")
		(18 "In8.Cu" signal "L9GND")
		(20 "In9.Cu" signal "L10")
		(22 "In10.Cu" signal "L11GND")
		(24 "In11.Cu" signal "L12")
		(26 "In12.Cu" signal "L13GND")
		(2 "B.Cu" signal "BOTTOM")
		(9 "F.Adhes" user "F.Adhesive")
		(11 "B.Adhes" user "B.Adhesive")
		(13 "F.Paste" user "Package Geometry/Pastemask Top")
		(15 "B.Paste" user "Package Geometry/Pastemask Bottom")
		(5 "F.SilkS" user "Ref Des/Silkscreen Top")
		(7 "B.SilkS" user "Ref Des/Silkscreen Bottom")
		(1 "F.Mask" user "Board Geometry/Soldermask Top")
		(3 "B.Mask" user "Board Geometry/Soldermask Bottom")
		(17 "Dwgs.User" user "User.Drawings")
		(19 "Cmts.User" user "User.Comments")
		(21 "Eco1.User" user "User.Eco1")
		(23 "Eco2.User" user "User.Eco2")
		(25 "Edge.Cuts" user "Board Geometry/Outline")
		(27 "Margin" user)
		(31 "F.CrtYd" user "Package Geometry/Place Bound Top")
		(29 "B.CrtYd" user "Package Geometry/Place Bound Bottom")
		(35 "F.Fab" user "Ref Des/Assembly Top")
		(33 "B.Fab" user "Ref Des/Assembly Bottom")
	)
	(footprint ""
		(layer "B.Cu")
		(at 486.114344 -58.908696 90)
		(property "Reference" "R30W1"
			(at 0.8382 -0.67818 90)
			(unlocked yes)
			(layer "B.SilkS")
			(effects
				(font
					(size 0.4064 0.254)
					(thickness 0.1524)
				)
				(justify left mirror)
			)
		)
		(property "Value" ""
			(at 0 0 90)
			(layer "B.Fab")
			(effects
				(font
					(size 1.27 1.27)
				)
				(justify mirror)
			)
		)
		(duplicate_pad_numbers_are_jumpers no)
		(fp_poly
			(pts
				(xy 0.2794 -0.1016) (xy -0.2794 -0.1016) (xy -0.2794 0.9906) (xy 0.2794 0.9906)
			)
			(stroke
				(width 0)
				(type default)
			)
			(fill no)
			(layer "B.CrtYd")
		)
		(fp_line
			(start 0.2794 -0.1016)
			(end 0.2794 0.9906)
			(stroke
				(width 0.1)
				(type default)
			)
			(layer "B.Fab")
		)
		(fp_line
			(start -0.2794 -0.1016)
			(end 0.2794 -0.1016)
			(stroke
				(width 0.1)
				(type default)
			)
			(layer "B.Fab")
		)
		(fp_line
			(start 0.2794 0.9906)
			(end -0.2794 0.9906)
			(stroke
				(width 0.1)
				(type default)
			)
			(layer "B.Fab")
		)
		(fp_line
			(start -0.2794 0.9906)
			(end -0.2794 -0.1016)
			(stroke
				(width 0.1)
				(type default)
			)
			(layer "B.Fab")
		)
		(pad "1" smd rect
			(at 0 0 270)
			(size 0.508 0.508)
			(layers "B.Cu" "B.Mask" "B.Paste")
			(net "USB3_P01_RXN")
		)
		(pad "2" smd rect
			(at 0 0.889 270)
			(size 0.508 0.508)
			(layers "B.Cu" "B.Mask" "B.Paste")
			(net "USB3_P01_FB_RXN")
		)
		(zone
			(layer "B.Cu")
			(hatch none 0.5)
			(connect_pads
				(clearance 0)
			)
			(min_thickness 0.25)
			(keepout
				(tracks allowed)
				(vias not_allowed)
				(pads allowed)
				(copperpour not_allowed)
				(footprints allowed)
			)
			(placement
				(enabled no)
				(sheetname "")
			)
			(fill
				(thermal_gap 0.5)
				(thermal_bridge_width 0.5)
				(island_removal_mode 0)
			)
			(polygon
				(pts
					(xy 486.368344 -59.162696) (xy 486.368344 -58.654696) (xy 486.749344 -58.654696) (xy 486.749344 -59.162696)
				)
			)
		)
		(zone
			(layer "B.Cu")
			(hatch none 0.5)
			(connect_pads
				(clearance 0)
			)
			(min_thickness 0.25)
			(keepout
				(tracks not_allowed)
				(vias allowed)
				(pads allowed)
				(copperpour not_allowed)
				(footprints allowed)
			)
			(placement
				(enabled no)
				(sheetname "")
			)
			(fill
				(thermal_gap 0.5)
				(thermal_bridge_width 0.5)
				(island_removal_mode 0)
			)
			(polygon
				(pts
					(xy 486.749344 -59.162696) (xy 486.749344 -58.654696) (xy 486.368344 -58.654696) (xy 486.368344 -59.162696)
				)
			)
		)
	)
	(footprint ""
		(layer "B.Cu")
		(at 386.13715 -111.05515 180)
		(property "Reference" "C3N6"
			(at 0 0 0)
			(layer "B.SilkS")
			(hide yes)
			(effects
				(font
					(size 1.27 1.27)
				)
				(justify mirror)
			)
		)
		(property "Value" ""
			(at 0 0 0)
			(layer "B.Fab")
			(effects
				(font
					(size 1.27 1.27)
				)
				(justify mirror)
			)
		)
		(duplicate_pad_numbers_are_jumpers no)
		(fp_rect
			(start 0.2794 0.9144)
			(end -0.2794 -0.1143)
			(stroke
				(width 0)
				(type default)
			)
			(fill no)
			(layer "B.CrtYd")
		)
		(fp_line
			(start 0.2794 0.9144)
			(end 0.2794 -0.1143)
			(stroke
				(width 0.1)
				(type default)
			)
			(layer "B.Fab")
		)
		(fp_line
			(start 0.2794 -0.1143)
			(end -0.2794 -0.1143)
			(stroke
				(width 0.1)
				(type default)
			)
			(layer "B.Fab")
		)
		(fp_line
			(start -0.2794 0.9144)
			(end 0.2794 0.9144)
			(stroke
				(width 0.1)
				(type default)
			)
			(layer "B.Fab")
		)
		(fp_line
			(start -0.2794 -0.1143)
			(end -0.2794 0.9144)
			(stroke
				(width 0.1)
				(type default)
			)
			(layer "B.Fab")
		)
		(pad "1" smd custom
			(at 0 0 90)
			(size 0.10414 0.10414)
			(layers "B.Cu" "B.Mask" "B.Paste")
			(net "PVNN_PCH_STBY")
			(options
				(clearance outline)
				(anchor circle)
			)
			(primitives
				(gr_poly
					(pts
						(xy -0.20828 -0.08636) (xy -0.20828 0.08636) (xy -0.08636 0.20828) (xy 0.086614 0.20828) (xy 0.20828 0.086614)
						(xy 0.20828 -0.08636) (xy 0.08636 -0.20828) (xy -0.08636 -0.20828)
					)
					(width 0)
					(fill yes)
				)
			)
		)
		(pad "2" smd custom
			(at 0 0.8001 90)
			(size 0.10414 0.10414)
			(layers "B.Cu" "B.Mask" "B.Paste")
			(net "GND")
			(options
				(clearance outline)
				(anchor circle)
			)
			(primitives
				(gr_poly
					(pts
						(xy -0.20828 -0.08636) (xy -0.20828 0.08636) (xy -0.08636 0.20828) (xy 0.086614 0.20828) (xy 0.20828 0.086614)
						(xy 0.20828 -0.08636) (xy 0.08636 -0.20828) (xy -0.08636 -0.20828)
					)
					(width 0)
					(fill yes)
				)
			)
		)
		(zone
			(layer "B.Cu")
			(hatch none 0.5)
			(connect_pads
				(clearance 0)
			)
			(min_thickness 0.25)
			(keepout
				(tracks not_allowed)
				(vias allowed)
				(pads allowed)
				(copperpour not_allowed)
				(footprints allowed)
			)
			(placement
				(enabled no)
				(sheetname "")
			)
			(fill
				(thermal_gap 0.5)
				(thermal_bridge_width 0.5)
				(island_removal_mode 0)
			)
			(polygon
				(pts
					(xy 386.04952 -111.2647) (xy 386.04952 -111.6457) (xy 386.22478 -111.6457) (xy 386.225034 -111.2647)
				)
			)
		)
		(zone
			(layer "B.Cu")
			(hatch none 0.5)
			(connect_pads
				(clearance 0)
			)
			(min_thickness 0.25)
			(keepout
				(tracks allowed)
				(vias not_allowed)
				(pads allowed)
				(copperpour not_allowed)
				(footprints allowed)
			)
			(placement
				(enabled no)
				(sheetname "")
			)
			(fill
				(thermal_gap 0.5)
				(thermal_bridge_width 0.5)
				(island_removal_mode 0)
			)
			(polygon
				(pts
					(xy 386.04952 -111.2647) (xy 386.04952 -111.6457) (xy 386.22478 -111.6457) (xy 386.225034 -111.2647)
				)
			)
		)
	)
	(footprint ""
		(layer "B.Cu")
		(at 45.212 -78.867 -90)
		(property "Reference" "C9P8"
			(at -0.60833 -3.429 0)
			(unlocked yes)
			(layer "B.SilkS")
			(effects
				(font
					(size 0.7874 0.5842)
					(thickness 0.1524)
				)
				(justify mirror)
			)
		)
		(property "Value" ""
			(at 0 0 90)
			(layer "B.Fab")
			(effects
				(font
					(size 1.27 1.27)
				)
				(justify mirror)
			)
		)
		(duplicate_pad_numbers_are_jumpers no)
		(fp_line
			(start -2.286 7.366)
			(end -1.600708 7.366)
			(stroke
				(width 0.1524)
				(type default)
			)
			(layer "B.SilkS")
		)
		(fp_line
			(start -2.286 7.366)
			(end -2.286 1.63195)
			(stroke
				(width 0.1524)
				(type default)
			)
			(layer "B.SilkS")
		)
		(fp_line
			(start 2.286 7.366)
			(end 1.60147 7.366)
			(stroke
				(width 0.1524)
				(type default)
			)
			(layer "B.SilkS")
		)
		(fp_line
			(start 2.286 7.366)
			(end 2.286 1.632712)
			(stroke
				(width 0.1524)
				(type default)
			)
			(layer "B.SilkS")
		)
		(fp_line
			(start -2.504948 1.633728)
			(end -1.6002 1.633728)
			(stroke
				(width 0.1524)
				(type default)
			)
			(layer "B.SilkS")
		)
		(fp_line
			(start 2.563114 1.633728)
			(end 1.6002 1.633728)
			(stroke
				(width 0.1524)
				(type default)
			)
			(layer "B.SilkS")
		)
		(fp_line
			(start -2.504948 -1.616456)
			(end -2.504948 1.633728)
			(stroke
				(width 0.1524)
				(type default)
			)
			(layer "B.SilkS")
		)
		(fp_line
			(start -1.6002 -1.616456)
			(end -2.504948 -1.616456)
			(stroke
				(width 0.1524)
				(type default)
			)
			(layer "B.SilkS")
		)
		(fp_line
			(start 1.6002 -1.616456)
			(end 2.563114 -1.616456)
			(stroke
				(width 0.1524)
				(type default)
			)
			(layer "B.SilkS")
		)
		(fp_line
			(start 2.563114 -1.616456)
			(end 2.563114 1.633728)
			(stroke
				(width 0.1524)
				(type default)
			)
			(layer "B.SilkS")
		)
		(fp_rect
			(start 2.286 7.366)
			(end -2.286 -0.254)
			(stroke
				(width 0)
				(type default)
			)
			(fill no)
			(layer "B.CrtYd")
		)
		(fp_line
			(start -2.286 7.366)
			(end 2.286 7.366)
			(stroke
				(width 0.1)
				(type default)
			)
			(layer "B.Fab")
		)
		(fp_line
			(start 2.286 7.366)
			(end 2.286 -0.254)
			(stroke
				(width 0.1)
				(type default)
			)
			(layer "B.Fab")
		)
		(fp_line
			(start -2.286 -0.254)
			(end -2.286 7.366)
			(stroke
				(width 0.1)
				(type default)
			)
			(layer "B.Fab")
		)
		(fp_line
			(start 2.286 -0.254)
			(end -2.286 -0.254)
			(stroke
				(width 0.1)
				(type default)
			)
			(layer "B.Fab")
		)
		(pad "1" smd rect
			(at 0 0 90)
			(size 2.54 3.048)
			(layers "B.Cu" "B.Mask" "B.Paste")
			(net "PVCCIN_CPU1")
		)
		(pad "2" smd rect
			(at 0 7.112 90)
			(size 2.54 3.048)
			(layers "B.Cu" "B.Mask" "B.Paste")
			(net "GND")
		)
	)
	(footprint ""
		(layer "B.Cu")
		(at 258.445 -8.0772 -90)
		(property "Reference" "C5U11"
			(at 0 0 90)
			(layer "B.SilkS")
			(hide yes)
			(effects
				(font
					(size 1.27 1.27)
				)
				(justify mirror)
			)
		)
		(property "Value" ""
			(at 0 0 90)
			(layer "B.Fab")
			(effects
				(font
					(size 1.27 1.27)
				)
				(justify mirror)
			)
		)
		(duplicate_pad_numbers_are_jumpers no)
		(fp_rect
			(start 0.500126 1.598422)
			(end -0.500126 -0.201422)
			(stroke
				(width 0)
				(type default)
			)
			(fill no)
			(layer "B.CrtYd")
		)
		(fp_line
			(start -0.500126 1.598422)
			(end 0.500126 1.598422)
			(stroke
				(width 0.1)
				(type default)
			)
			(layer "B.Fab")
		)
		(fp_line
			(start 0.500126 1.598422)
			(end 0.500126 -0.201422)
			(stroke
				(width 0.1)
				(type default)
			)
			(layer "B.Fab")
		)
		(fp_line
			(start -0.500126 -0.201422)
			(end -0.500126 1.598422)
			(stroke
				(width 0.1)
				(type default)
			)
			(layer "B.Fab")
		)
		(fp_line
			(start 0.500126 -0.201422)
			(end -0.500126 -0.201422)
			(stroke
				(width 0.1)
				(type default)
			)
			(layer "B.Fab")
		)
		(pad "1" smd rect
			(at 0 0 180)
			(size 0.889 0.9906)
			(layers "B.Cu" "B.Mask" "B.Paste")
			(net "PVDDQ_ABC")
		)
		(pad "2" smd rect
			(at 0 1.397 180)
			(size 0.889 0.9906)
			(layers "B.Cu" "B.Mask" "B.Paste")
			(net "GND")
		)
		(zone
			(layer "B.Cu")
			(hatch none 0.5)
			(connect_pads
				(clearance 0)
			)
			(min_thickness 0.25)
			(keepout
				(tracks allowed)
				(vias not_allowed)
				(pads allowed)
				(copperpour not_allowed)
				(footprints allowed)
			)
			(placement
				(enabled no)
				(sheetname "")
			)
			(fill
				(thermal_gap 0.5)
				(thermal_bridge_width 0.5)
				(island_removal_mode 0)
			)
			(polygon
				(pts
					(xy 257.4925 -7.5819) (xy 258.0005 -7.5819) (xy 258.0005 -8.5725) (xy 257.4925 -8.5725)
				)
			)
		)
		(zone
			(layer "B.Cu")
			(hatch none 0.5)
			(connect_pads
				(clearance 0)
			)
			(min_thickness 0.25)
			(keepout
				(tracks not_allowed)
				(vias allowed)
				(pads allowed)
				(copperpour not_allowed)
				(footprints allowed)
			)
			(placement
				(enabled no)
				(sheetname "")
			)
			(fill
				(thermal_gap 0.5)
				(thermal_bridge_width 0.5)
				(island_removal_mode 0)
			)
			(polygon
				(pts
					(xy 257.4925 -7.5819) (xy 258.0005 -7.5819) (xy 258.0005 -8.5725) (xy 257.4925 -8.5725)
				)
			)
		)
	)
	(footprint ""
		(layer "B.Cu")
		(at 343.125806 -60.368434)
		(property "Reference" "R2U21"
			(at 0 0 0)
			(layer "B.SilkS")
			(hide yes)
			(effects
				(font
					(size 1.27 1.27)
				)
				(justify mirror)
			)
		)
		(property "Value" ""
			(at 0 0 0)
			(layer "B.Fab")
			(effects
				(font
					(size 1.27 1.27)
				)
				(justify mirror)
			)
		)
		(duplicate_pad_numbers_are_jumpers no)
		(fp_poly
			(pts
				(xy 0.2794 -0.1016) (xy -0.2794 -0.1016) (xy -0.2794 0.9906) (xy 0.2794 0.9906)
			)
			(stroke
				(width 0)
				(type default)
			)
			(fill no)
			(layer "B.CrtYd")
		)
		(fp_line
			(start -0.2794 -0.1016)
			(end 0.2794 -0.1016)
			(stroke
				(width 0.1)
				(type default)
			)
			(layer "B.Fab")
		)
		(fp_line
			(start -0.2794 0.9906)
			(end -0.2794 -0.1016)
			(stroke
				(width 0.1)
				(type default)
			)
			(layer "B.Fab")
		)
		(fp_line
			(start 0.2794 -0.1016)
			(end 0.2794 0.9906)
			(stroke
				(width 0.1)
				(type default)
			)
			(layer "B.Fab")
		)
		(fp_line
			(start 0.2794 0.9906)
			(end -0.2794 0.9906)
			(stroke
				(width 0.1)
				(type default)
			)
			(layer "B.Fab")
		)
		(pad "1" smd rect
			(at 0 0 180)
			(size 0.508 0.508)
			(layers "B.Cu" "B.Mask" "B.Paste")
			(net "P3E_CPU0_PE1_SS_RXN<3>")
		)
		(pad "2" smd rect
			(at 0 0.889 180)
			(size 0.508 0.508)
			(layers "B.Cu" "B.Mask" "B.Paste")
			(net "P3E_CPU0_PE1_SS_R_RXN<3>")
		)
		(zone
			(layer "B.Cu")
			(hatch none 0.5)
			(connect_pads
				(clearance 0)
			)
			(min_thickness 0.25)
			(keepout
				(tracks allowed)
				(vias not_allowed)
				(pads allowed)
				(copperpour not_allowed)
				(footprints allowed)
			)
			(placement
				(enabled no)
				(sheetname "")
			)
			(fill
				(thermal_gap 0.5)
				(thermal_bridge_width 0.5)
				(island_removal_mode 0)
			)
			(polygon
				(pts
					(xy 343.379806 -60.114434) (xy 342.871806 -60.114434) (xy 342.871806 -59.733434) (xy 343.379806 -59.733434)
				)
			)
		)
		(zone
			(layer "B.Cu")
			(hatch none 0.5)
			(connect_pads
				(clearance 0)
			)
			(min_thickness 0.25)
			(keepout
				(tracks not_allowed)
				(vias allowed)
				(pads allowed)
				(copperpour not_allowed)
				(footprints allowed)
			)
			(placement
				(enabled no)
				(sheetname "")
			)
			(fill
				(thermal_gap 0.5)
				(thermal_bridge_width 0.5)
				(island_removal_mode 0)
			)
			(polygon
				(pts
					(xy 343.379806 -59.733434) (xy 342.871806 -59.733434) (xy 342.871806 -60.114434) (xy 343.379806 -60.114434)
				)
			)
		)
	)
	(footprint ""
		(layer "B.Cu")
		(at 17.83842 -105.20172 90)
		(property "Reference" "C9N6"
			(at 0 0 90)
			(layer "B.SilkS")
			(hide yes)
			(effects
				(font
					(size 1.27 1.27)
				)
				(justify mirror)
			)
		)
		(property "Value" ""
			(at 0 0 90)
			(layer "B.Fab")
			(effects
				(font
					(size 1.27 1.27)
				)
				(justify mirror)
			)
		)
		(duplicate_pad_numbers_are_jumpers no)
		(fp_poly
			(pts
				(xy -0.3048 -0.1016) (xy -0.3048 0.9906) (xy 0.3048 0.9906) (xy 0.3048 -0.1016)
			)
			(stroke
				(width 0)
				(type default)
			)
			(fill no)
			(layer "B.CrtYd")
		)
		(fp_line
			(start 0.3048 -0.1016)
			(end 0.3048 0.9906)
			(stroke
				(width 0.1)
				(type default)
			)
			(layer "B.Fab")
		)
		(fp_line
			(start -0.3048 -0.1016)
			(end 0.3048 -0.1016)
			(stroke
				(width 0.1)
				(type default)
			)
			(layer "B.Fab")
		)
		(fp_line
			(start 0.3048 0.9906)
			(end -0.3048 0.9906)
			(stroke
				(width 0.1)
				(type default)
			)
			(layer "B.Fab")
		)
		(fp_line
			(start -0.3048 0.9906)
			(end -0.3048 -0.1016)
			(stroke
				(width 0.1)
				(type default)
			)
			(layer "B.Fab")
		)
		(pad "1" smd rect
			(at 0 0 270)
			(size 0.508 0.508)
			(layers "B.Cu" "B.Mask" "B.Paste")
			(net "P3E_CPU1_PE3_MP_C_TXN<13>")
		)
		(pad "2" smd rect
			(at 0 0.889 270)
			(size 0.508 0.508)
			(layers "B.Cu" "B.Mask" "B.Paste")
			(net "P3E_CPU1_PE3_MP_TXN<13>")
		)
		(zone
			(layer "B.Cu")
			(hatch none 0.5)
			(connect_pads
				(clearance 0)
			)
			(min_thickness 0.25)
			(keepout
				(tracks allowed)
				(vias not_allowed)
				(pads allowed)
				(copperpour not_allowed)
				(footprints allowed)
			)
			(placement
				(enabled no)
				(sheetname "")
			)
			(fill
				(thermal_gap 0.5)
				(thermal_bridge_width 0.5)
				(island_removal_mode 0)
			)
			(polygon
				(pts
					(xy 18.09242 -105.45572) (xy 18.09242 -104.94772) (xy 18.47342 -104.94772) (xy 18.47342 -105.45572)
				)
			)
		)
		(zone
			(layer "B.Cu")
			(hatch none 0.5)
			(connect_pads
				(clearance 0)
			)
			(min_thickness 0.25)
			(keepout
				(tracks not_allowed)
				(vias allowed)
				(pads allowed)
				(copperpour not_allowed)
				(footprints allowed)
			)
			(placement
				(enabled no)
				(sheetname "")
			)
			(fill
				(thermal_gap 0.5)
				(thermal_bridge_width 0.5)
				(island_removal_mode 0)
			)
			(polygon
				(pts
					(xy 18.47342 -105.45572) (xy 18.47342 -104.94772) (xy 18.09242 -104.94772) (xy 18.09242 -105.45572)
				)
			)
		)
	)
	(footprint ""
		(layer "B.Cu")
		(at 498.602 -138.557 90)
		(property "Reference" "R1L43"
			(at 0 0 90)
			(layer "B.SilkS")
			(hide yes)
			(effects
				(font
					(size 1.27 1.27)
				)
				(justify mirror)
			)
		)
		(property "Value" ""
			(at 0 0 90)
			(layer "B.Fab")
			(effects
				(font
					(size 1.27 1.27)
				)
				(justify mirror)
			)
		)
		(duplicate_pad_numbers_are_jumpers no)
		(fp_poly
			(pts
				(xy 0.2794 -0.1016) (xy -0.2794 -0.1016) (xy -0.2794 0.9906) (xy 0.2794 0.9906)
			)
			(stroke
				(width 0)
				(type default)
			)
			(fill no)
			(layer "B.CrtYd")
		)
		(fp_line
			(start 0.2794 -0.1016)
			(end 0.2794 0.9906)
			(stroke
				(width 0.1)
				(type default)
			)
			(layer "B.Fab")
		)
		(fp_line
			(start -0.2794 -0.1016)
			(end 0.2794 -0.1016)
			(stroke
				(width 0.1)
				(type default)
			)
			(layer "B.Fab")
		)
		(fp_line
			(start 0.2794 0.9906)
			(end -0.2794 0.9906)
			(stroke
				(width 0.1)
				(type default)
			)
			(layer "B.Fab")
		)
		(fp_line
			(start -0.2794 0.9906)
			(end -0.2794 -0.1016)
			(stroke
				(width 0.1)
				(type default)
			)
			(layer "B.Fab")
		)
		(pad "1" smd rect
			(at 0 0 270)
			(size 0.508 0.508)
			(layers "B.Cu" "B.Mask" "B.Paste")
			(net "FM_UARTSW_LSB_R_N")
		)
		(pad "2" smd rect
			(at 0 0.889 270)
			(size 0.508 0.508)
			(layers "B.Cu" "B.Mask" "B.Paste")
			(net "P3V3_STBY")
		)
		(zone
			(layer "B.Cu")
			(hatch none 0.5)
			(connect_pads
				(clearance 0)
			)
			(min_thickness 0.25)
			(keepout
				(tracks allowed)
				(vias not_allowed)
				(pads allowed)
				(copperpour not_allowed)
				(footprints allowed)
			)
			(placement
				(enabled no)
				(sheetname "")
			)
			(fill
				(thermal_gap 0.5)
				(thermal_bridge_width 0.5)
				(island_removal_mode 0)
			)
			(polygon
				(pts
					(xy 498.856 -138.811) (xy 498.856 -138.303) (xy 499.237 -138.303) (xy 499.237 -138.811)
				)
			)
		)
		(zone
			(layer "B.Cu")
			(hatch none 0.5)
			(connect_pads
				(clearance 0)
			)
			(min_thickness 0.25)
			(keepout
				(tracks not_allowed)
				(vias allowed)
				(pads allowed)
				(copperpour not_allowed)
				(footprints allowed)
			)
			(placement
				(enabled no)
				(sheetname "")
			)
			(fill
				(thermal_gap 0.5)
				(thermal_bridge_width 0.5)
				(island_removal_mode 0)
			)
			(polygon
				(pts
					(xy 499.237 -138.811) (xy 499.237 -138.303) (xy 498.856 -138.303) (xy 498.856 -138.811)
				)
			)
		)
	)
)
